(kicad_pcb
	(version 20260206)
	(generator "pcbnew")
	(generator_version "10.0")
	(general
		(thickness 1.6)
		(legacy_teardrops no)
	)
	(paper "A4")
	(title_block
		(title "01162023_DA0F0TEBIF0_F0T_Expander_BD_F_brd_V02_OCP.brd")
		(comment 1 "Grand Teton / footprints 9006-9014 of 9728")
	)
	(layers
		(0 "F.Cu" signal "TOP")
		(4 "In1.Cu" signal "GND")
		(6 "In2.Cu" signal "VCC")
		(8 "In3.Cu" signal "VCC1")
		(10 "In4.Cu" signal "GND1")
		(12 "In5.Cu" signal "IN1")
		(14 "In6.Cu" signal "GND2")
		(16 "In7.Cu" signal "IN2")
		(18 "In8.Cu" signal "GND3")
		(20 "In9.Cu" signal "IN3")
		(22 "In10.Cu" signal "GND4")
		(24 "In11.Cu" signal "IN4")
		(26 "In12.Cu" signal "GND5")
		(28 "In13.Cu" signal "IN5")
		(30 "In14.Cu" signal "GND6")
		(32 "In15.Cu" signal "IN6")
		(34 "In16.Cu" signal "GND7")
		(2 "B.Cu" signal "BOTTOM")
		(9 "F.Adhes" user "F.Adhesive")
		(11 "B.Adhes" user "B.Adhesive")
		(13 "F.Paste" user "Package Geometry/Pastemask Top")
		(15 "B.Paste" user "Package Geometry/Pastemask Bottom")
		(5 "F.SilkS" user "Ref Des/Silkscreen Top")
		(7 "B.SilkS" user "Ref Des/Silkscreen Bottom")
		(1 "F.Mask" user "Board Geometry/Soldermask Top")
		(3 "B.Mask" user "Board Geometry/Soldermask Bottom")
		(17 "Dwgs.User" user "User.Drawings")
		(19 "Cmts.User" user "User.Comments")
		(21 "Eco1.User" user "User.Eco1")
		(23 "Eco2.User" user "User.Eco2")
		(25 "Edge.Cuts" user "Board Geometry/Outline")
		(27 "Margin" user)
		(31 "F.CrtYd" user "Package Geometry/Place Bound Top")
		(29 "B.CrtYd" user "Package Geometry/Place Bound Bottom")
		(35 "F.Fab" user "Ref Des/Assembly Top")
		(33 "B.Fab" user "Ref Des/Assembly Bottom")
	)
	(footprint ""
		(layer "B.Cu")
		(at 378.741178 -225.092768 90)
		(property "Reference" "R6173"
			(at 0 0 90)
			(layer "B.SilkS")
			(hide yes)
			(effects
				(font
					(size 1.27 1.27)
				)
				(justify mirror)
			)
		)
		(property "Value" ""
			(at 0 0 90)
			(layer "B.Fab")
			(effects
				(font
					(size 1.27 1.27)
				)
				(justify mirror)
			)
		)
		(duplicate_pad_numbers_are_jumpers no)
		(fp_line
			(start 0.7874 -0.4064)
			(end -0.7874 -0.4064)
			(stroke
				(width 0.1524)
				(type default)
			)
			(layer "B.SilkS")
		)
		(fp_line
			(start -0.7874 -0.4064)
			(end -0.7874 0.4064)
			(stroke
				(width 0.1524)
				(type default)
			)
			(layer "B.SilkS")
		)
		(fp_line
			(start 0.7874 0.4064)
			(end 0.7874 -0.4064)
			(stroke
				(width 0.1524)
				(type default)
			)
			(layer "B.SilkS")
		)
		(fp_line
			(start -0.7874 0.4064)
			(end 0.7874 0.4064)
			(stroke
				(width 0.1524)
				(type default)
			)
			(layer "B.SilkS")
		)
		(fp_line
			(start 0.67945 -0.305054)
			(end 0.12065 -0.305054)
			(stroke
				(width 0.1)
				(type default)
			)
			(layer "B.Fab")
		)
		(fp_line
			(start 0.12065 -0.305054)
			(end 0.12065 -0.2794)
			(stroke
				(width 0.1)
				(type default)
			)
			(layer "B.Fab")
		)
		(fp_line
			(start -0.12065 -0.3048)
			(end -0.67945 -0.3048)
			(stroke
				(width 0.1)
				(type default)
			)
			(layer "B.Fab")
		)
		(fp_line
			(start -0.67945 -0.3048)
			(end -0.67945 0.3048)
			(stroke
				(width 0.1)
				(type default)
			)
			(layer "B.Fab")
		)
		(fp_line
			(start 0.12065 -0.2794)
			(end -0.12065 -0.2794)
			(stroke
				(width 0.1)
				(type default)
			)
			(layer "B.Fab")
		)
		(fp_line
			(start -0.12065 -0.2794)
			(end -0.12065 -0.3048)
			(stroke
				(width 0.1)
				(type default)
			)
			(layer "B.Fab")
		)
		(fp_line
			(start 0.12065 0.2794)
			(end 0.12065 0.3048)
			(stroke
				(width 0.1)
				(type default)
			)
			(layer "B.Fab")
		)
		(fp_line
			(start -0.120396 0.2794)
			(end 0.12065 0.2794)
			(stroke
				(width 0.1)
				(type default)
			)
			(layer "B.Fab")
		)
		(fp_line
			(start 0.67945 0.3048)
			(end 0.67945 -0.305054)
			(stroke
				(width 0.1)
				(type default)
			)
			(layer "B.Fab")
		)
		(fp_line
			(start 0.12065 0.3048)
			(end 0.67945 0.3048)
			(stroke
				(width 0.1)
				(type default)
			)
			(layer "B.Fab")
		)
		(fp_line
			(start -0.120396 0.3048)
			(end -0.120396 0.2794)
			(stroke
				(width 0.1)
				(type default)
			)
			(layer "B.Fab")
		)
		(fp_line
			(start -0.67945 0.3048)
			(end -0.120396 0.3048)
			(stroke
				(width 0.1)
				(type default)
			)
			(layer "B.Fab")
		)
		(pad "1" smd circle
			(at 0.40005 0 270)
			(size 0 0)
			(layers "B.Cu" "B.Mask" "B.Paste")
			(net "SPI_PEX3_RST_R_N")
		)
		(pad "2" smd circle
			(at -0.40005 0 270)
			(size 0 0)
			(layers "B.Cu" "B.Mask" "B.Paste")
			(net "GND")
		)
	)
	(footprint ""
		(layer "B.Cu")
		(at 163.874958 -291.149786 90)
		(property "Reference" "C3233"
			(at 0 0 90)
			(layer "B.SilkS")
			(hide yes)
			(effects
				(font
					(size 1.27 1.27)
				)
				(justify mirror)
			)
		)
		(property "Value" ""
			(at 0 0 90)
			(layer "B.Fab")
			(effects
				(font
					(size 1.27 1.27)
				)
				(justify mirror)
			)
		)
		(duplicate_pad_numbers_are_jumpers no)
		(fp_line
			(start 0.299974 -0.150114)
			(end -0.299974 -0.150114)
			(stroke
				(width 0.1)
				(type default)
			)
			(layer "B.Fab")
		)
		(fp_line
			(start -0.299974 -0.150114)
			(end -0.299974 0.150114)
			(stroke
				(width 0.1)
				(type default)
			)
			(layer "B.Fab")
		)
		(fp_line
			(start 0.299974 0.150114)
			(end 0.299974 -0.150114)
			(stroke
				(width 0.1)
				(type default)
			)
			(layer "B.Fab")
		)
		(fp_line
			(start -0.299974 0.150114)
			(end 0.299974 0.150114)
			(stroke
				(width 0.1)
				(type default)
			)
			(layer "B.Fab")
		)
		(pad "1" smd rect
			(at 0.2667 0 270)
			(size 0.3048 0.381)
			(layers "B.Cu" "B.Mask" "B.Paste")
			(net "PCEPLL7_VDDA18_PEX1")
		)
		(pad "2" smd rect
			(at -0.2667 0 270)
			(size 0.3048 0.381)
			(layers "B.Cu" "B.Mask" "B.Paste")
			(net "GND")
		)
	)
	(footprint ""
		(layer "B.Cu")
		(at 217.235786 -213.222586 180)
		(property "Reference" "R5770"
			(at 0 0 0)
			(layer "B.SilkS")
			(hide yes)
			(effects
				(font
					(size 1.27 1.27)
				)
				(justify mirror)
			)
		)
		(property "Value" ""
			(at 0 0 0)
			(layer "B.Fab")
			(effects
				(font
					(size 1.27 1.27)
				)
				(justify mirror)
			)
		)
		(duplicate_pad_numbers_are_jumpers no)
		(fp_line
			(start 0.7874 0.4064)
			(end 0.7874 -0.4064)
			(stroke
				(width 0.1524)
				(type default)
			)
			(layer "B.SilkS")
		)
		(fp_line
			(start 0.7874 -0.4064)
			(end -0.7874 -0.4064)
			(stroke
				(width 0.1524)
				(type default)
			)
			(layer "B.SilkS")
		)
		(fp_line
			(start -0.7874 0.4064)
			(end 0.7874 0.4064)
			(stroke
				(width 0.1524)
				(type default)
			)
			(layer "B.SilkS")
		)
		(fp_line
			(start -0.7874 -0.4064)
			(end -0.7874 0.4064)
			(stroke
				(width 0.1524)
				(type default)
			)
			(layer "B.SilkS")
		)
		(fp_line
			(start 0.67945 0.3048)
			(end 0.67945 -0.305054)
			(stroke
				(width 0.1)
				(type default)
			)
			(layer "B.Fab")
		)
		(fp_line
			(start 0.67945 -0.305054)
			(end 0.12065 -0.305054)
			(stroke
				(width 0.1)
				(type default)
			)
			(layer "B.Fab")
		)
		(fp_line
			(start 0.12065 0.3048)
			(end 0.67945 0.3048)
			(stroke
				(width 0.1)
				(type default)
			)
			(layer "B.Fab")
		)
		(fp_line
			(start 0.12065 0.2794)
			(end 0.12065 0.3048)
			(stroke
				(width 0.1)
				(type default)
			)
			(layer "B.Fab")
		)
		(fp_line
			(start 0.12065 -0.2794)
			(end -0.12065 -0.2794)
			(stroke
				(width 0.1)
				(type default)
			)
			(layer "B.Fab")
		)
		(fp_line
			(start 0.12065 -0.305054)
			(end 0.12065 -0.2794)
			(stroke
				(width 0.1)
				(type default)
			)
			(layer "B.Fab")
		)
		(fp_line
			(start -0.120396 0.3048)
			(end -0.120396 0.2794)
			(stroke
				(width 0.1)
				(type default)
			)
			(layer "B.Fab")
		)
		(fp_line
			(start -0.120396 0.2794)
			(end 0.12065 0.2794)
			(stroke
				(width 0.1)
				(type default)
			)
			(layer "B.Fab")
		)
		(fp_line
			(start -0.12065 -0.2794)
			(end -0.12065 -0.3048)
			(stroke
				(width 0.1)
				(type default)
			)
			(layer "B.Fab")
		)
		(fp_line
			(start -0.12065 -0.3048)
			(end -0.67945 -0.3048)
			(stroke
				(width 0.1)
				(type default)
			)
			(layer "B.Fab")
		)
		(fp_line
			(start -0.67945 0.3048)
			(end -0.120396 0.3048)
			(stroke
				(width 0.1)
				(type default)
			)
			(layer "B.Fab")
		)
		(fp_line
			(start -0.67945 -0.3048)
			(end -0.67945 0.3048)
			(stroke
				(width 0.1)
				(type default)
			)
			(layer "B.Fab")
		)
		(pad "1" smd circle
			(at 0.40005 0)
			(size 0 0)
			(layers "B.Cu" "B.Mask" "B.Paste")
			(net "RST_BIC_USB_HUB_R_N")
		)
		(pad "2" smd circle
			(at -0.40005 0)
			(size 0 0)
			(layers "B.Cu" "B.Mask" "B.Paste")
			(net "RST_BIC_USB_HUB_N")
		)
	)
	(footprint ""
		(layer "B.Cu")
		(at 295.20134 -305.399948 -90)
		(property "Reference" "C3321"
			(at 0 0 90)
			(layer "B.SilkS")
			(hide yes)
			(effects
				(font
					(size 1.27 1.27)
				)
				(justify mirror)
			)
		)
		(property "Value" ""
			(at 0 0 90)
			(layer "B.Fab")
			(effects
				(font
					(size 1.27 1.27)
				)
				(justify mirror)
			)
		)
		(duplicate_pad_numbers_are_jumpers no)
		(fp_line
			(start -0.299974 0.150114)
			(end 0.299974 0.150114)
			(stroke
				(width 0.1)
				(type default)
			)
			(layer "B.Fab")
		)
		(fp_line
			(start 0.299974 0.150114)
			(end 0.299974 -0.150114)
			(stroke
				(width 0.1)
				(type default)
			)
			(layer "B.Fab")
		)
		(fp_line
			(start -0.299974 -0.150114)
			(end -0.299974 0.150114)
			(stroke
				(width 0.1)
				(type default)
			)
			(layer "B.Fab")
		)
		(fp_line
			(start 0.299974 -0.150114)
			(end -0.299974 -0.150114)
			(stroke
				(width 0.1)
				(type default)
			)
			(layer "B.Fab")
		)
		(pad "1" smd rect
			(at 0.2667 0 90)
			(size 0.3048 0.381)
			(layers "B.Cu" "B.Mask" "B.Paste")
			(net "P1V25_SERDES_VDDPLL_PEX2")
		)
		(pad "2" smd rect
			(at -0.2667 0 90)
			(size 0.3048 0.381)
			(layers "B.Cu" "B.Mask" "B.Paste")
			(net "GND")
		)
	)
	(footprint ""
		(layer "B.Cu")
		(at 296.124884 -293.99992 -90)
		(property "Reference" "C1655"
			(at 0 0 90)
			(layer "B.SilkS")
			(hide yes)
			(effects
				(font
					(size 1.27 1.27)
				)
				(justify mirror)
			)
		)
		(property "Value" ""
			(at 0 0 90)
			(layer "B.Fab")
			(effects
				(font
					(size 1.27 1.27)
				)
				(justify mirror)
			)
		)
		(duplicate_pad_numbers_are_jumpers no)
		(fp_line
			(start -0.299974 0.150114)
			(end 0.299974 0.150114)
			(stroke
				(width 0.1)
				(type default)
			)
			(layer "B.Fab")
		)
		(fp_line
			(start 0.299974 0.150114)
			(end 0.299974 -0.150114)
			(stroke
				(width 0.1)
				(type default)
			)
			(layer "B.Fab")
		)
		(fp_line
			(start -0.299974 -0.150114)
			(end -0.299974 0.150114)
			(stroke
				(width 0.1)
				(type default)
			)
			(layer "B.Fab")
		)
		(fp_line
			(start 0.299974 -0.150114)
			(end -0.299974 -0.150114)
			(stroke
				(width 0.1)
				(type default)
			)
			(layer "B.Fab")
		)
		(pad "1" smd rect
			(at 0.2667 0 90)
			(size 0.3048 0.381)
			(layers "B.Cu" "B.Mask" "B.Paste")
			(net "P0V8_PEX2")
		)
		(pad "2" smd rect
			(at -0.2667 0 90)
			(size 0.3048 0.381)
			(layers "B.Cu" "B.Mask" "B.Paste")
			(net "GND")
		)
	)
	(footprint ""
		(layer "B.Cu")
		(at 234.048046 -154.143202 90)
		(property "Reference" "L79"
			(at 0 0 90)
			(layer "B.SilkS")
			(hide yes)
			(effects
				(font
					(size 1.27 1.27)
				)
				(justify mirror)
			)
		)
		(property "Value" ""
			(at 0 0 90)
			(layer "B.Fab")
			(effects
				(font
					(size 1.27 1.27)
				)
				(justify mirror)
			)
		)
		(duplicate_pad_numbers_are_jumpers no)
		(fp_line
			(start 1.63576 -0.8128)
			(end -1.63576 -0.8128)
			(stroke
				(width 0.1524)
				(type default)
			)
			(layer "B.SilkS")
		)
		(fp_line
			(start 1.63576 -0.8128)
			(end 1.63576 0.8128)
			(stroke
				(width 0.1524)
				(type default)
			)
			(layer "B.SilkS")
		)
		(fp_line
			(start -1.63576 -0.8128)
			(end -1.63576 0.8128)
			(stroke
				(width 0.1524)
				(type default)
			)
			(layer "B.SilkS")
		)
		(fp_line
			(start -1.63576 0.8128)
			(end 1.63576 0.8128)
			(stroke
				(width 0.1524)
				(type default)
			)
			(layer "B.SilkS")
		)
		(fp_line
			(start 1.56083 -0.738632)
			(end 1.56083 0.7366)
			(stroke
				(width 0.1)
				(type default)
			)
			(layer "B.Fab")
		)
		(fp_line
			(start -1.560576 -0.738632)
			(end 1.56083 -0.738632)
			(stroke
				(width 0.1)
				(type default)
			)
			(layer "B.Fab")
		)
		(fp_line
			(start 1.56083 0.7366)
			(end 1.524 0.7366)
			(stroke
				(width 0.1)
				(type default)
			)
			(layer "B.Fab")
		)
		(fp_line
			(start 1.524 0.7366)
			(end -1.524 0.7366)
			(stroke
				(width 0.1)
				(type default)
			)
			(layer "B.Fab")
		)
		(fp_line
			(start -1.524 0.7366)
			(end -1.560576 0.7366)
			(stroke
				(width 0.1)
				(type default)
			)
			(layer "B.Fab")
		)
		(fp_line
			(start -1.560576 0.7366)
			(end -1.560576 -0.738632)
			(stroke
				(width 0.1)
				(type default)
			)
			(layer "B.Fab")
		)
		(pad "1" smd rect
			(at 0.94996 0 90)
			(size 1.1176 1.3716)
			(layers "B.Cu" "B.Mask" "B.Paste")
			(net "P3V3")
		)
		(pad "2" smd rect
			(at -0.94996 0 90)
			(size 1.1176 1.3716)
			(layers "B.Cu" "B.Mask" "B.Paste")
			(net "P3V3_CLK_GEN_VDD_CK440_PEX")
		)
	)
	(footprint ""
		(layer "B.Cu")
		(at 178.599846 -303.499774 -90)
		(property "Reference" "C3085"
			(at 0 0 90)
			(layer "B.SilkS")
			(hide yes)
			(effects
				(font
					(size 1.27 1.27)
				)
				(justify mirror)
			)
		)
		(property "Value" ""
			(at 0 0 90)
			(layer "B.Fab")
			(effects
				(font
					(size 1.27 1.27)
				)
				(justify mirror)
			)
		)
		(duplicate_pad_numbers_are_jumpers no)
		(fp_line
			(start -0.299974 0.150114)
			(end 0.299974 0.150114)
			(stroke
				(width 0.1)
				(type default)
			)
			(layer "B.Fab")
		)
		(fp_line
			(start 0.299974 0.150114)
			(end 0.299974 -0.150114)
			(stroke
				(width 0.1)
				(type default)
			)
			(layer "B.Fab")
		)
		(fp_line
			(start -0.299974 -0.150114)
			(end -0.299974 0.150114)
			(stroke
				(width 0.1)
				(type default)
			)
			(layer "B.Fab")
		)
		(fp_line
			(start 0.299974 -0.150114)
			(end -0.299974 -0.150114)
			(stroke
				(width 0.1)
				(type default)
			)
			(layer "B.Fab")
		)
		(pad "1" smd rect
			(at 0.2667 0 90)
			(size 0.3048 0.381)
			(layers "B.Cu" "B.Mask" "B.Paste")
			(net "P1V25_PEX1")
		)
		(pad "2" smd rect
			(at -0.2667 0 90)
			(size 0.3048 0.381)
			(layers "B.Cu" "B.Mask" "B.Paste")
			(net "GND")
		)
	)
	(footprint ""
		(layer "B.Cu")
		(at 255.63068 -89.904316 180)
		(property "Reference" "R1047"
			(at 0 0 0)
			(layer "B.SilkS")
			(hide yes)
			(effects
				(font
					(size 1.27 1.27)
				)
				(justify mirror)
			)
		)
		(property "Value" ""
			(at 0 0 0)
			(layer "B.Fab")
			(effects
				(font
					(size 1.27 1.27)
				)
				(justify mirror)
			)
		)
		(duplicate_pad_numbers_are_jumpers no)
		(fp_line
			(start 1.2954 0.5842)
			(end 1.2954 -0.5842)
			(stroke
				(width 0.1524)
				(type default)
			)
			(layer "B.SilkS")
		)
		(fp_line
			(start 1.2954 -0.5842)
			(end -1.2954 -0.5842)
			(stroke
				(width 0.1524)
				(type default)
			)
			(layer "B.SilkS")
		)
		(fp_line
			(start -1.2954 0.5842)
			(end 1.2954 0.5842)
			(stroke
				(width 0.1524)
				(type default)
			)
			(layer "B.SilkS")
		)
		(fp_line
			(start -1.2954 -0.5842)
			(end -1.2954 0.5842)
			(stroke
				(width 0.1524)
				(type default)
			)
			(layer "B.SilkS")
		)
		(fp_line
			(start 1.1938 0.4064)
			(end 1.1938 -0.406654)
			(stroke
				(width 0.1)
				(type default)
			)
			(layer "B.Fab")
		)
		(fp_line
			(start 1.1938 -0.406654)
			(end 0.8636 -0.406654)
			(stroke
				(width 0.1)
				(type default)
			)
			(layer "B.Fab")
		)
		(fp_line
			(start 0.8636 0.4572)
			(end 0.8636 0.4318)
			(stroke
				(width 0.1)
				(type default)
			)
			(layer "B.Fab")
		)
		(fp_line
			(start 0.8636 0.4318)
			(end 0.8636 0.4064)
			(stroke
				(width 0.1)
				(type default)
			)
			(layer "B.Fab")
		)
		(fp_line
			(start 0.8636 0.4064)
			(end 1.1938 0.4064)
			(stroke
				(width 0.1)
				(type default)
			)
			(layer "B.Fab")
		)
		(fp_line
			(start 0.8636 -0.406654)
			(end 0.8636 -0.4572)
			(stroke
				(width 0.1)
				(type default)
			)
			(layer "B.Fab")
		)
		(fp_line
			(start 0.8636 -0.4572)
			(end -0.8636 -0.4572)
			(stroke
				(width 0.1)
				(type default)
			)
			(layer "B.Fab")
		)
		(fp_line
			(start -0.8636 0.4572)
			(end 0.8636 0.4572)
			(stroke
				(width 0.1)
				(type default)
			)
			(layer "B.Fab")
		)
		(fp_line
			(start -0.8636 0.4064)
			(end -0.8636 0.4572)
			(stroke
				(width 0.1)
				(type default)
			)
			(layer "B.Fab")
		)
		(fp_line
			(start -0.8636 -0.406654)
			(end -1.1938 -0.406654)
			(stroke
				(width 0.1)
				(type default)
			)
			(layer "B.Fab")
		)
		(fp_line
			(start -0.8636 -0.4572)
			(end -0.8636 -0.406654)
			(stroke
				(width 0.1)
				(type default)
			)
			(layer "B.Fab")
		)
		(fp_line
			(start -1.1938 0.4064)
			(end -0.8636 0.4064)
			(stroke
				(width 0.1)
				(type default)
			)
			(layer "B.Fab")
		)
		(fp_line
			(start -1.1938 -0.406654)
			(end -1.1938 0.4064)
			(stroke
				(width 0.1)
				(type default)
			)
			(layer "B.Fab")
		)
		(pad "1" smd rect
			(at 0.7366 0 90)
			(size 0.7112 0.8128)
			(layers "B.Cu" "B.Mask" "B.Paste")
			(net "P3V3_CLK_GEN_VDDXTAL_CK440")
		)
		(pad "2" smd rect
			(at -0.7366 0 90)
			(size 0.7112 0.8128)
			(layers "B.Cu" "B.Mask" "B.Paste")
			(net "P3V3_CLK_GEN_VDDA25M_CK440")
		)
	)
	(footprint ""
		(layer "B.Cu")
		(at 335.309464 -219.234512 180)
		(property "Reference" "C2080"
			(at 0 0 0)
			(layer "B.SilkS")
			(hide yes)
			(effects
				(font
					(size 1.27 1.27)
				)
				(justify mirror)
			)
		)
		(property "Value" ""
			(at 0 0 0)
			(layer "B.Fab")
			(effects
				(font
					(size 1.27 1.27)
				)
				(justify mirror)
			)
		)
		(duplicate_pad_numbers_are_jumpers no)
		(fp_line
			(start 0.69215 0.2921)
			(end 0.69215 -0.2921)
			(stroke
				(width 0.1524)
				(type default)
			)
			(layer "B.SilkS")
		)
		(fp_line
			(start 0.69215 -0.2921)
			(end -0.69215 -0.2921)
			(stroke
				(width 0.1524)
				(type default)
			)
			(layer "B.SilkS")
		)
		(fp_line
			(start -0.69215 0.2921)
			(end 0.69215 0.2921)
			(stroke
				(width 0.1524)
				(type default)
			)
			(layer "B.SilkS")
		)
		(fp_line
			(start -0.69215 -0.2921)
			(end -0.69215 0.2921)
			(stroke
				(width 0.1524)
				(type default)
			)
			(layer "B.SilkS")
		)
		(fp_line
			(start 0.51435 0.2794)
			(end 0.51435 -0.2794)
			(stroke
				(width 0.1)
				(type default)
			)
			(layer "B.Fab")
		)
		(fp_line
			(start 0.51435 -0.2794)
			(end -0.51435 -0.2794)
			(stroke
				(width 0.1)
				(type default)
			)
			(layer "B.Fab")
		)
		(fp_line
			(start -0.51435 0.2794)
			(end 0.51435 0.2794)
			(stroke
				(width 0.1)
				(type default)
			)
			(layer "B.Fab")
		)
		(fp_line
			(start -0.51435 -0.2794)
			(end -0.51435 0.2794)
			(stroke
				(width 0.1)
				(type default)
			)
			(layer "B.Fab")
		)
		(pad "1" smd circle
			(at 0.40005 0)
			(size 0 0)
			(layers "B.Cu" "B.Mask" "B.Paste")
			(net "P3V3_FPGA_VCCIO4")
		)
		(pad "2" smd circle
			(at -0.40005 0)
			(size 0 0)
			(layers "B.Cu" "B.Mask" "B.Paste")
			(net "GND")
		)
		(zone
			(layer "B.Cu")
			(hatch none 0.5)
			(connect_pads
				(clearance 0)
			)
			(min_thickness 0.25)
			(keepout
				(tracks not_allowed)
				(vias allowed)
				(pads allowed)
				(copperpour not_allowed)
				(footprints allowed)
			)
			(placement
				(enabled no)
				(sheetname "")
			)
			(fill
				(thermal_gap 0.5)
				(thermal_bridge_width 0.5)
				(island_removal_mode 0)
			)
			(polygon
				(pts
					(xy 335.118964 -219.322142) (xy 335.210404 -219.380308) (xy 335.409794 -219.380308) (xy 335.499964 -219.322142)
					(xy 335.499964 -219.146882) (xy 335.409794 -219.088462) (xy 335.210404 -219.088462) (xy 335.118964 -219.146628)
				)
			)
		)
	)
)
